(kicad_pcb
	(version 20260206)
	(generator "pcbnew")
	(generator_version "10.0")
	(general
		(thickness 1.6)
		(legacy_teardrops no)
	)
	(paper "A4")
	(title_block
		(title "baseboard — 13948-1b.1110WZS1818.brd")
		(comment 1 "Honey Badger (Wiwynn) / footprints 1365-1372 of 2523")
	)
	(layers
		(0 "F.Cu" signal "TOP")
		(4 "In1.Cu" signal "L2GND")
		(6 "In2.Cu" signal "L3")
		(8 "In3.Cu" signal "L4VCC")
		(10 "In4.Cu" signal "L5VCC")
		(12 "In5.Cu" signal "L6")
		(14 "In6.Cu" signal "L7GND")
		(2 "B.Cu" signal "BOTTOM")
		(9 "F.Adhes" user "F.Adhesive")
		(11 "B.Adhes" user "B.Adhesive")
		(13 "F.Paste" user "Package Geometry/Pastemask Top")
		(15 "B.Paste" user "Package Geometry/Pastemask Bottom")
		(5 "F.SilkS" user "Ref Des/Silkscreen Top")
		(7 "B.SilkS" user "Ref Des/Silkscreen Bottom")
		(1 "F.Mask" user "Board Geometry/Soldermask Top")
		(3 "B.Mask" user "Board Geometry/Soldermask Bottom")
		(17 "Dwgs.User" user "User.Drawings")
		(19 "Cmts.User" user "User.Comments")
		(21 "Eco1.User" user "User.Eco1")
		(23 "Eco2.User" user "User.Eco2")
		(25 "Edge.Cuts" user "Board Geometry/Outline")
		(27 "Margin" user)
		(31 "F.CrtYd" user "Package Geometry/Place Bound Top")
		(29 "B.CrtYd" user "Package Geometry/Place Bound Bottom")
		(35 "F.Fab" user "Ref Des/Assembly Top")
		(33 "B.Fab" user "Ref Des/Assembly Bottom")
	)
	(footprint ""
		(layer "F.Cu")
		(at 98.56597 -78.105)
		(property "Reference" "STP145"
			(at 0 0 0)
			(layer "F.SilkS")
			(hide yes)
			(effects
				(font
					(size 1.27 1.27)
				)
			)
		)
		(property "Value" "TPAD28"
			(at 0.0127 -1.8034 0)
			(unlocked yes)
			(layer "F.Fab")
			(hide yes)
			(effects
				(font
					(size 1.016 1.016)
					(thickness 0.1524)
				)
			)
		)
		(property "Device Type" "TPAD28"
			(at 0.0127 -3.3274 0)
			(unlocked yes)
			(layer "F.Fab")
			(hide yes)
			(effects
				(font
					(size 1.016 1.016)
					(thickness 0.1524)
				)
			)
		)
		(duplicate_pad_numbers_are_jumpers no)
		(fp_poly
			(pts
				(arc
					(start 0.3556 0)
					(mid -0.3556 0)
					(end 0.3556 0)
				)
			)
			(stroke
				(width 0)
				(type default)
			)
			(fill no)
			(layer "F.CrtYd")
		)
		(fp_poly
			(pts
				(arc
					(start 0.6096 0)
					(mid -0.6096 0)
					(end 0.6096 0)
				)
			)
			(stroke
				(width 0)
				(type default)
			)
			(fill no)
			(layer "F.Fab")
		)
		(pad "1" smd circle
			(at 0 0)
			(size 0.7112 0.7112)
			(layers "F.Cu" "F.Mask" "F.Paste")
			(net "SXP_ACTIVE_0")
		)
	)
	(footprint ""
		(layer "F.Cu")
		(at 164.719 -101.473 180)
		(property "Reference" "PC180"
			(at 0 0 180)
			(layer "F.SilkS")
			(hide yes)
			(effects
				(font
					(size 1.27 1.27)
				)
			)
		)
		(property "Value" "SC47U6D3V5MX-1-GP"
			(at -0.0762 -6.1214 180)
			(unlocked yes)
			(layer "F.Fab")
			(hide yes)
			(effects
				(font
					(size 1.016 1.016)
					(thickness 0.1524)
				)
			)
		)
		(property "Device Type" "C805H54"
			(at -0.0762 -8.1534 180)
			(unlocked yes)
			(layer "F.Fab")
			(hide yes)
			(effects
				(font
					(size 1.016 1.016)
					(thickness 0.1524)
				)
			)
		)
		(duplicate_pad_numbers_are_jumpers no)
		(fp_line
			(start 0.635 0)
			(end -0.635 0)
			(stroke
				(width 0.508)
				(type default)
			)
			(layer "F.SilkS")
		)
		(fp_rect
			(start -0.9652 1.778)
			(end 0.9652 -1.778)
			(stroke
				(width 0)
				(type default)
			)
			(fill no)
			(layer "F.CrtYd")
		)
		(fp_poly
			(pts
				(xy -0.9652 -1.778) (xy 0.9652 -1.778) (xy 0.9652 1.778) (xy -0.9652 1.778)
			)
			(stroke
				(width 0)
				(type default)
			)
			(fill no)
			(layer "F.Fab")
		)
		(pad "1" smd rect
			(at 0 -0.9652 180)
			(size 1.397 1.143)
			(layers "F.Cu" "F.Mask" "F.Paste")
			(net "P0V9_E")
		)
		(pad "2" smd rect
			(at 0 0.9652 180)
			(size 1.397 1.143)
			(layers "F.Cu" "F.Mask" "F.Paste")
			(net "GND")
		)
	)
	(footprint ""
		(layer "F.Cu")
		(at 331.851 -218.059 -90)
		(property "Reference" "C145"
			(at 0 0 270)
			(layer "F.SilkS")
			(hide yes)
			(effects
				(font
					(size 1.27 1.27)
				)
			)
		)
		(property "Value" "SC1U10V2KX-4-GP"
			(at 1.1811 -2.7051 270)
			(unlocked yes)
			(layer "F.Fab")
			(hide yes)
			(effects
				(font
					(size 1.016 1.016)
					(thickness 0.1524)
				)
			)
		)
		(property "Device Type" "C402H22"
			(at 1.1811 -4.2291 270)
			(unlocked yes)
			(layer "F.Fab")
			(hide yes)
			(effects
				(font
					(size 1.016 1.016)
					(thickness 0.1524)
				)
			)
		)
		(duplicate_pad_numbers_are_jumpers no)
		(fp_rect
			(start -0.4318 0.9525)
			(end 0.4318 -0.9525)
			(stroke
				(width 0)
				(type default)
			)
			(fill no)
			(layer "F.CrtYd")
		)
		(fp_rect
			(start -0.4318 0.9525)
			(end 0.4318 -0.9525)
			(stroke
				(width 0)
				(type default)
			)
			(fill no)
			(layer "F.Fab")
		)
		(pad "1" smd custom
			(at 0 -0.4445 270)
			(size 0.1524 0.1524)
			(layers "F.Cu" "F.Mask" "F.Paste")
			(net "P3V3_STBY")
			(options
				(clearance outline)
				(anchor circle)
			)
			(primitives
				(gr_poly
					(pts
						(arc
							(start 0.3048 -0.2032)
							(mid 0.275042 -0.275042)
							(end 0.2032 -0.3048)
						)
						(arc
							(start -0.2032 -0.3048)
							(mid -0.275042 -0.275042)
							(end -0.3048 -0.2032)
						)
						(arc
							(start -0.3048 0.2032)
							(mid -0.275042 0.275042)
							(end -0.2032 0.3048)
						)
						(arc
							(start 0.2032 0.3048)
							(mid 0.275042 0.275042)
							(end 0.3048 0.2032)
						)
					)
					(width 0)
					(fill yes)
				)
			)
		)
		(pad "2" smd custom
			(at 0 0.4445 270)
			(size 0.1524 0.1524)
			(layers "F.Cu" "F.Mask" "F.Paste")
			(net "GND")
			(options
				(clearance outline)
				(anchor circle)
			)
			(primitives
				(gr_poly
					(pts
						(arc
							(start 0.3048 -0.2032)
							(mid 0.275042 -0.275042)
							(end 0.2032 -0.3048)
						)
						(arc
							(start -0.2032 -0.3048)
							(mid -0.275042 -0.275042)
							(end -0.3048 -0.2032)
						)
						(arc
							(start -0.3048 0.2032)
							(mid -0.275042 0.275042)
							(end -0.2032 0.3048)
						)
						(arc
							(start 0.2032 0.3048)
							(mid 0.275042 0.275042)
							(end 0.3048 0.2032)
						)
					)
					(width 0)
					(fill yes)
				)
			)
		)
	)
	(footprint ""
		(layer "F.Cu")
		(at 87.865966 -88.011 180)
		(property "Reference" "SC1149"
			(at 0 0 180)
			(layer "F.SilkS")
			(hide yes)
			(effects
				(font
					(size 1.27 1.27)
				)
			)
		)
		(property "Value" "SCD1U6D3V1KX-GP"
			(at -2.8321 -1.7399 180)
			(unlocked yes)
			(layer "F.Fab")
			(hide yes)
			(effects
				(font
					(size 1.016 1.016)
					(thickness 0.1524)
				)
			)
		)
		(property "Device Type" "C0201H13"
			(at -2.8321 -3.2639 180)
			(unlocked yes)
			(layer "F.Fab")
			(hide yes)
			(effects
				(font
					(size 1.016 1.016)
					(thickness 0.1524)
				)
			)
		)
		(duplicate_pad_numbers_are_jumpers no)
		(fp_rect
			(start -0.2794 0.6477)
			(end 0.2794 -0.6477)
			(stroke
				(width 0)
				(type default)
			)
			(fill no)
			(layer "F.CrtYd")
		)
		(fp_rect
			(start -0.2794 0.6477)
			(end 0.2794 -0.6477)
			(stroke
				(width 0)
				(type default)
			)
			(fill no)
			(layer "F.Fab")
		)
		(pad "1" smd custom
			(at 0 -0.2794 180)
			(size 0.0762 0.0762)
			(layers "F.Cu" "F.Mask" "F.Paste")
			(net "SYSPLL_VDDA18")
			(options
				(clearance outline)
				(anchor circle)
			)
			(primitives
				(gr_poly
					(pts
						(arc
							(start 0.1524 -0.127)
							(mid 0.137521 -0.162921)
							(end 0.1016 -0.1778)
						)
						(arc
							(start -0.1016 -0.1778)
							(mid -0.137521 -0.162921)
							(end -0.1524 -0.127)
						)
						(arc
							(start -0.1524 0.127)
							(mid -0.137521 0.162921)
							(end -0.1016 0.1778)
						)
						(arc
							(start 0.1016 0.1778)
							(mid 0.137521 0.162921)
							(end 0.1524 0.127)
						)
					)
					(width 0)
					(fill yes)
				)
			)
		)
		(pad "2" smd custom
			(at 0 0.2794 180)
			(size 0.0762 0.0762)
			(layers "F.Cu" "F.Mask" "F.Paste")
			(net "GND")
			(options
				(clearance outline)
				(anchor circle)
			)
			(primitives
				(gr_poly
					(pts
						(arc
							(start 0.1524 -0.127)
							(mid 0.137521 -0.162921)
							(end 0.1016 -0.1778)
						)
						(arc
							(start -0.1016 -0.1778)
							(mid -0.137521 -0.162921)
							(end -0.1524 -0.127)
						)
						(arc
							(start -0.1524 0.127)
							(mid -0.137521 0.162921)
							(end -0.1016 0.1778)
						)
						(arc
							(start 0.1016 0.1778)
							(mid 0.137521 0.162921)
							(end 0.1524 0.127)
						)
					)
					(width 0)
					(fill yes)
				)
			)
		)
	)
	(footprint ""
		(layer "F.Cu")
		(at 68.707 -54.102 180)
		(property "Reference" "SC967"
			(at 0 0 180)
			(layer "F.SilkS")
			(hide yes)
			(effects
				(font
					(size 1.27 1.27)
				)
			)
		)
		(property "Value" "SC1U10V2KX-4-GP"
			(at 1.1811 -2.7051 180)
			(unlocked yes)
			(layer "F.Fab")
			(hide yes)
			(effects
				(font
					(size 1.016 1.016)
					(thickness 0.1524)
				)
			)
		)
		(property "Device Type" "C402H22"
			(at 1.1811 -4.2291 180)
			(unlocked yes)
			(layer "F.Fab")
			(hide yes)
			(effects
				(font
					(size 1.016 1.016)
					(thickness 0.1524)
				)
			)
		)
		(duplicate_pad_numbers_are_jumpers no)
		(fp_rect
			(start -0.4318 0.9525)
			(end 0.4318 -0.9525)
			(stroke
				(width 0)
				(type default)
			)
			(fill no)
			(layer "F.CrtYd")
		)
		(fp_rect
			(start -0.4318 0.9525)
			(end 0.4318 -0.9525)
			(stroke
				(width 0)
				(type default)
			)
			(fill no)
			(layer "F.Fab")
		)
		(pad "1" smd custom
			(at 0 -0.4445 180)
			(size 0.1524 0.1524)
			(layers "F.Cu" "F.Mask" "F.Paste")
			(net "P1V8_C")
			(options
				(clearance outline)
				(anchor circle)
			)
			(primitives
				(gr_poly
					(pts
						(arc
							(start 0.3048 -0.2032)
							(mid 0.275042 -0.275042)
							(end 0.2032 -0.3048)
						)
						(arc
							(start -0.2032 -0.3048)
							(mid -0.275042 -0.275042)
							(end -0.3048 -0.2032)
						)
						(arc
							(start -0.3048 0.2032)
							(mid -0.275042 0.275042)
							(end -0.2032 0.3048)
						)
						(arc
							(start 0.2032 0.3048)
							(mid 0.275042 0.275042)
							(end 0.3048 0.2032)
						)
					)
					(width 0)
					(fill yes)
				)
			)
		)
		(pad "2" smd custom
			(at 0 0.4445 180)
			(size 0.1524 0.1524)
			(layers "F.Cu" "F.Mask" "F.Paste")
			(net "GND")
			(options
				(clearance outline)
				(anchor circle)
			)
			(primitives
				(gr_poly
					(pts
						(arc
							(start 0.3048 -0.2032)
							(mid 0.275042 -0.275042)
							(end 0.2032 -0.3048)
						)
						(arc
							(start -0.2032 -0.3048)
							(mid -0.275042 -0.275042)
							(end -0.3048 -0.2032)
						)
						(arc
							(start -0.3048 0.2032)
							(mid -0.275042 0.275042)
							(end -0.2032 0.3048)
						)
						(arc
							(start 0.2032 0.3048)
							(mid 0.275042 0.275042)
							(end 0.3048 0.2032)
						)
					)
					(width 0)
					(fill yes)
				)
			)
		)
	)
	(footprint ""
		(layer "F.Cu")
		(at 53.218842 -132.380482 90)
		(property "Reference" "SR784"
			(at 0 0 90)
			(layer "F.SilkS")
			(hide yes)
			(effects
				(font
					(size 1.27 1.27)
				)
			)
		)
		(property "Value" "10KR2F-2-GP"
			(at 0.064008 -3.993896 90)
			(unlocked yes)
			(layer "F.Fab")
			(hide yes)
			(effects
				(font
					(size 1.016 1.016)
					(thickness 0.1524)
				)
			)
		)
		(property "Device Type" "R402H16"
			(at 0.064008 -5.517896 90)
			(unlocked yes)
			(layer "F.Fab")
			(hide yes)
			(effects
				(font
					(size 1.016 1.016)
					(thickness 0.1524)
				)
			)
		)
		(duplicate_pad_numbers_are_jumpers no)
		(fp_line
			(start 0.508 -0.9398)
			(end -0.508 -0.9398)
			(stroke
				(width 0.1524)
				(type default)
			)
			(layer "F.SilkS")
		)
		(fp_line
			(start -0.508 -0.9398)
			(end -0.508 0.9398)
			(stroke
				(width 0.1524)
				(type default)
			)
			(layer "F.SilkS")
		)
		(fp_rect
			(start -0.508 0.9398)
			(end 0.508 -0.9398)
			(stroke
				(width 0)
				(type default)
			)
			(fill no)
			(layer "F.CrtYd")
		)
		(fp_rect
			(start -0.508 0.9398)
			(end 0.508 -0.9398)
			(stroke
				(width 0)
				(type default)
			)
			(fill no)
			(layer "F.Fab")
		)
		(pad "1" smd custom
			(at 0 -0.4445 90)
			(size 0.1397 0.1397)
			(layers "F.Cu" "F.Mask" "F.Paste")
			(net "P1V8_E")
			(options
				(clearance outline)
				(anchor circle)
			)
			(primitives
				(gr_poly
					(pts
						(arc
							(start -0.1778 -0.2794)
							(mid -0.249642 -0.249642)
							(end -0.2794 -0.1778)
						)
						(arc
							(start -0.2794 0.1778)
							(mid -0.249642 0.249642)
							(end -0.1778 0.2794)
						)
						(arc
							(start 0.1778 0.2794)
							(mid 0.249642 0.249642)
							(end 0.2794 0.1778)
						)
						(arc
							(start 0.2794 -0.1778)
							(mid 0.249642 -0.249642)
							(end 0.1778 -0.2794)
						)
					)
					(width 0)
					(fill yes)
				)
			)
		)
		(pad "2" smd custom
			(at 0 0.4445 90)
			(size 0.1397 0.1397)
			(layers "F.Cu" "F.Mask" "F.Paste")
			(net "EXP_WP_N")
			(options
				(clearance outline)
				(anchor circle)
			)
			(primitives
				(gr_poly
					(pts
						(arc
							(start -0.1778 -0.2794)
							(mid -0.249642 -0.249642)
							(end -0.2794 -0.1778)
						)
						(arc
							(start -0.2794 0.1778)
							(mid -0.249642 0.249642)
							(end -0.1778 0.2794)
						)
						(arc
							(start 0.1778 0.2794)
							(mid 0.249642 0.249642)
							(end 0.2794 0.1778)
						)
						(arc
							(start 0.2794 -0.1778)
							(mid 0.249642 -0.249642)
							(end 0.1778 -0.2794)
						)
					)
					(width 0)
					(fill yes)
				)
			)
		)
	)
	(footprint ""
		(layer "F.Cu")
		(at 19.508216 -181.91988 180)
		(property "Reference" "R650"
			(at 0 0 180)
			(layer "F.SilkS")
			(hide yes)
			(effects
				(font
					(size 1.27 1.27)
				)
			)
		)
		(property "Value" "4K7R2F-GP"
			(at 0.064008 -3.993896 180)
			(unlocked yes)
			(layer "F.Fab")
			(hide yes)
			(effects
				(font
					(size 1.016 1.016)
					(thickness 0.1524)
				)
			)
		)
		(property "Device Type" "R402H16"
			(at 0.064008 -5.517896 180)
			(unlocked yes)
			(layer "F.Fab")
			(hide yes)
			(effects
				(font
					(size 1.016 1.016)
					(thickness 0.1524)
				)
			)
		)
		(duplicate_pad_numbers_are_jumpers no)
		(fp_line
			(start 0.508 -0.9398)
			(end -0.508 -0.9398)
			(stroke
				(width 0.1524)
				(type default)
			)
			(layer "F.SilkS")
		)
		(fp_line
			(start -0.508 -0.9398)
			(end -0.508 0.9398)
			(stroke
				(width 0.1524)
				(type default)
			)
			(layer "F.SilkS")
		)
		(fp_rect
			(start -0.508 0.9398)
			(end 0.508 -0.9398)
			(stroke
				(width 0)
				(type default)
			)
			(fill no)
			(layer "F.CrtYd")
		)
		(fp_rect
			(start -0.508 0.9398)
			(end 0.508 -0.9398)
			(stroke
				(width 0)
				(type default)
			)
			(fill no)
			(layer "F.Fab")
		)
		(pad "1" smd custom
			(at 0 -0.4445 180)
			(size 0.1397 0.1397)
			(layers "F.Cu" "F.Mask" "F.Paste")
			(net "P3V3_STBY")
			(options
				(clearance outline)
				(anchor circle)
			)
			(primitives
				(gr_poly
					(pts
						(arc
							(start -0.1778 -0.2794)
							(mid -0.249642 -0.249642)
							(end -0.2794 -0.1778)
						)
						(arc
							(start -0.2794 0.1778)
							(mid -0.249642 0.249642)
							(end -0.1778 0.2794)
						)
						(arc
							(start 0.1778 0.2794)
							(mid 0.249642 0.249642)
							(end 0.2794 0.1778)
						)
						(arc
							(start 0.2794 -0.1778)
							(mid 0.249642 -0.249642)
							(end 0.1778 -0.2794)
						)
					)
					(width 0)
					(fill yes)
				)
			)
		)
		(pad "2" smd custom
			(at 0 0.4445 180)
			(size 0.1397 0.1397)
			(layers "F.Cu" "F.Mask" "F.Paste")
			(net "IO_EXP_HDD_PRE_A3")
			(options
				(clearance outline)
				(anchor circle)
			)
			(primitives
				(gr_poly
					(pts
						(arc
							(start -0.1778 -0.2794)
							(mid -0.249642 -0.249642)
							(end -0.2794 -0.1778)
						)
						(arc
							(start -0.2794 0.1778)
							(mid -0.249642 0.249642)
							(end -0.1778 0.2794)
						)
						(arc
							(start 0.1778 0.2794)
							(mid 0.249642 0.249642)
							(end 0.2794 0.1778)
						)
						(arc
							(start 0.2794 -0.1778)
							(mid 0.249642 -0.249642)
							(end 0.1778 -0.2794)
						)
					)
					(width 0)
					(fill yes)
				)
			)
		)
	)
	(footprint ""
		(layer "F.Cu")
		(at 292.481 -161.544)
		(property "Reference" "R612"
			(at 0 0 0)
			(layer "F.SilkS")
			(hide yes)
			(effects
				(font
					(size 1.27 1.27)
				)
			)
		)
		(property "Value" "0R2J-2-GP"
			(at 0.064008 -3.993896 0)
			(unlocked yes)
			(layer "F.Fab")
			(hide yes)
			(effects
				(font
					(size 1.016 1.016)
					(thickness 0.1524)
				)
			)
		)
		(property "Device Type" "R402H16"
			(at 0.064008 -5.517896 0)
			(unlocked yes)
			(layer "F.Fab")
			(hide yes)
			(effects
				(font
					(size 1.016 1.016)
					(thickness 0.1524)
				)
			)
		)
		(duplicate_pad_numbers_are_jumpers no)
		(fp_line
			(start -0.508 -0.9398)
			(end -0.508 0.9398)
			(stroke
				(width 0.1524)
				(type default)
			)
			(layer "F.SilkS")
		)
		(fp_line
			(start 0.508 -0.9398)
			(end -0.508 -0.9398)
			(stroke
				(width 0.1524)
				(type default)
			)
			(layer "F.SilkS")
		)
		(fp_rect
			(start -0.508 0.9398)
			(end 0.508 -0.9398)
			(stroke
				(width 0)
				(type default)
			)
			(fill no)
			(layer "F.CrtYd")
		)
		(fp_rect
			(start -0.508 0.9398)
			(end 0.508 -0.9398)
			(stroke
				(width 0)
				(type default)
			)
			(fill no)
			(layer "F.Fab")
		)
		(pad "1" smd custom
			(at 0 -0.4445)
			(size 0.1397 0.1397)
			(layers "F.Cu" "F.Mask" "F.Paste")
			(net "HDD_PRE_INT_R")
			(options
				(clearance outline)
				(anchor circle)
			)
			(primitives
				(gr_poly
					(pts
						(arc
							(start -0.1778 -0.2794)
							(mid -0.249642 -0.249642)
							(end -0.2794 -0.1778)
						)
						(arc
							(start -0.2794 0.1778)
							(mid -0.249642 0.249642)
							(end -0.1778 0.2794)
						)
						(arc
							(start 0.1778 0.2794)
							(mid 0.249642 0.249642)
							(end 0.2794 0.1778)
						)
						(arc
							(start 0.2794 -0.1778)
							(mid 0.249642 -0.249642)
							(end 0.1778 -0.2794)
						)
					)
					(width 0)
					(fill yes)
				)
			)
		)
		(pad "2" smd custom
			(at 0 0.4445)
			(size 0.1397 0.1397)
			(layers "F.Cu" "F.Mask" "F.Paste")
			(net "BMC_HDD_PRE_INT_N")
			(options
				(clearance outline)
				(anchor circle)
			)
			(primitives
				(gr_poly
					(pts
						(arc
							(start -0.1778 -0.2794)
							(mid -0.249642 -0.249642)
							(end -0.2794 -0.1778)
						)
						(arc
							(start -0.2794 0.1778)
							(mid -0.249642 0.249642)
							(end -0.1778 0.2794)
						)
						(arc
							(start 0.1778 0.2794)
							(mid 0.249642 0.249642)
							(end 0.2794 0.1778)
						)
						(arc
							(start 0.2794 -0.1778)
							(mid 0.249642 -0.249642)
							(end 0.1778 -0.2794)
						)
					)
					(width 0)
					(fill yes)
				)
			)
		)
	)
)
